(kicad_pcb
	(version 20260206)
	(generator "pcbnew")
	(generator_version "10.0")
	(general
		(thickness 1.6)
		(legacy_teardrops no)
	)
	(paper "A4")
	(title_block
		(title "Wiwynn_Tioga_Pass_MB.brd")
		(comment 1 "Tioga Pass / footprint 2167 of 4770 (J4G1), pads 244-291 of 291")
	)
	(layers
		(0 "F.Cu" signal "TOP")
		(4 "In1.Cu" signal "L2GND")
		(6 "In2.Cu" signal "L3")
		(8 "In3.Cu" signal "L4GND")
		(10 "In4.Cu" signal "L5")
		(12 "In5.Cu" signal "L6GND")
		(14 "In6.Cu" signal "L7VCC")
		(16 "In7.Cu" signal "L8VCC")
		(18 "In8.Cu" signal "L9GND")
		(20 "In9.Cu" signal "L10")
		(22 "In10.Cu" signal "L11GND")
		(24 "In11.Cu" signal "L12")
		(26 "In12.Cu" signal "L13GND")
		(2 "B.Cu" signal "BOTTOM")
		(9 "F.Adhes" user "F.Adhesive")
		(11 "B.Adhes" user "B.Adhesive")
		(13 "F.Paste" user "Package Geometry/Pastemask Top")
		(15 "B.Paste" user "Package Geometry/Pastemask Bottom")
		(5 "F.SilkS" user "Ref Des/Silkscreen Top")
		(7 "B.SilkS" user "Ref Des/Silkscreen Bottom")
		(1 "F.Mask" user "Board Geometry/Soldermask Top")
		(3 "B.Mask" user "Board Geometry/Soldermask Bottom")
		(17 "Dwgs.User" user "User.Drawings")
		(19 "Cmts.User" user "User.Comments")
		(21 "Eco1.User" user "User.Eco1")
		(23 "Eco2.User" user "User.Eco2")
		(25 "Edge.Cuts" user "Board Geometry/Outline")
		(27 "Margin" user)
		(31 "F.CrtYd" user "Package Geometry/Place Bound Top")
		(29 "B.CrtYd" user "Package Geometry/Place Bound Bottom")
		(35 "F.Fab" user "Ref Des/Assembly Top")
		(33 "B.Fab" user "Ref Des/Assembly Bottom")
	)
	(footprint ""
		(layer "F.Cu")
		(at 194.700398 -15.423642 90)
		(property "Reference" "J4G1"
			(at 9.060688 37.32911 0)
			(unlocked yes)
			(layer "F.SilkS")
			(effects
				(font
					(size 0.7874 0.5842)
					(thickness 0.1524)
				)
				(justify left)
			)
		)
		(property "Value" ""
			(at 0 0 90)
			(layer "F.Fab")
			(effects
				(font
					(size 1.27 1.27)
				)
			)
		)
		(duplicate_pad_numbers_are_jumpers no)
		(pad "241" smd rect
			(at 4.59994 86.700106 90)
			(size 1.8034 0.508)
			(layers "F.Cu" "F.Mask" "F.Paste")
			(net "GND")
		)
		(pad "242" smd rect
			(at 4.59994 87.54999 90)
			(size 1.8034 0.508)
			(layers "F.Cu" "F.Mask" "F.Paste")
			(net "M_A_DQ<32>")
		)
		(pad "243" smd rect
			(at 4.59994 88.399874 90)
			(size 1.8034 0.508)
			(layers "F.Cu" "F.Mask" "F.Paste")
			(net "GND")
		)
		(pad "244" smd rect
			(at 4.59994 89.250012 90)
			(size 1.8034 0.508)
			(layers "F.Cu" "F.Mask" "F.Paste")
			(net "M_A_DQS_DN<4>")
		)
		(pad "245" smd rect
			(at 4.59994 90.099896 90)
			(size 1.8034 0.508)
			(layers "F.Cu" "F.Mask" "F.Paste")
			(net "M_A_DQS_DP<4>")
		)
		(pad "246" smd rect
			(at 4.59994 90.950034 90)
			(size 1.8034 0.508)
			(layers "F.Cu" "F.Mask" "F.Paste")
			(net "GND")
		)
		(pad "247" smd rect
			(at 4.59994 91.799918 90)
			(size 1.8034 0.508)
			(layers "F.Cu" "F.Mask" "F.Paste")
			(net "M_A_DQ<38>")
		)
		(pad "248" smd rect
			(at 4.59994 92.650056 90)
			(size 1.8034 0.508)
			(layers "F.Cu" "F.Mask" "F.Paste")
			(net "GND")
		)
		(pad "249" smd rect
			(at 4.59994 93.49994 90)
			(size 1.8034 0.508)
			(layers "F.Cu" "F.Mask" "F.Paste")
			(net "M_A_DQ<34>")
		)
		(pad "250" smd rect
			(at 4.59994 94.350078 90)
			(size 1.8034 0.508)
			(layers "F.Cu" "F.Mask" "F.Paste")
			(net "GND")
		)
		(pad "251" smd rect
			(at 4.59994 95.199962 90)
			(size 1.8034 0.508)
			(layers "F.Cu" "F.Mask" "F.Paste")
			(net "M_A_DQ<44>")
		)
		(pad "252" smd rect
			(at 4.59994 96.0501 90)
			(size 1.8034 0.508)
			(layers "F.Cu" "F.Mask" "F.Paste")
			(net "GND")
		)
		(pad "253" smd rect
			(at 4.59994 96.899984 90)
			(size 1.8034 0.508)
			(layers "F.Cu" "F.Mask" "F.Paste")
			(net "M_A_DQ<40>")
		)
		(pad "254" smd rect
			(at 4.59994 97.750122 90)
			(size 1.8034 0.508)
			(layers "F.Cu" "F.Mask" "F.Paste")
			(net "GND")
		)
		(pad "255" smd rect
			(at 4.59994 98.600006 90)
			(size 1.8034 0.508)
			(layers "F.Cu" "F.Mask" "F.Paste")
			(net "M_A_DQS_DN<5>")
		)
		(pad "256" smd rect
			(at 4.59994 99.44989 90)
			(size 1.8034 0.508)
			(layers "F.Cu" "F.Mask" "F.Paste")
			(net "M_A_DQS_DP<5>")
		)
		(pad "257" smd rect
			(at 4.59994 100.300028 90)
			(size 1.8034 0.508)
			(layers "F.Cu" "F.Mask" "F.Paste")
			(net "GND")
		)
		(pad "258" smd rect
			(at 4.59994 101.149912 90)
			(size 1.8034 0.508)
			(layers "F.Cu" "F.Mask" "F.Paste")
			(net "M_A_DQ<46>")
		)
		(pad "259" smd rect
			(at 4.59994 102.00005 90)
			(size 1.8034 0.508)
			(layers "F.Cu" "F.Mask" "F.Paste")
			(net "GND")
		)
		(pad "260" smd rect
			(at 4.59994 102.849934 90)
			(size 1.8034 0.508)
			(layers "F.Cu" "F.Mask" "F.Paste")
			(net "M_A_DQ<42>")
		)
		(pad "261" smd rect
			(at 4.59994 103.700072 90)
			(size 1.8034 0.508)
			(layers "F.Cu" "F.Mask" "F.Paste")
			(net "GND")
		)
		(pad "262" smd rect
			(at 4.59994 104.549956 90)
			(size 1.8034 0.508)
			(layers "F.Cu" "F.Mask" "F.Paste")
			(net "M_A_DQ<52>")
		)
		(pad "263" smd rect
			(at 4.59994 105.400094 90)
			(size 1.8034 0.508)
			(layers "F.Cu" "F.Mask" "F.Paste")
			(net "GND")
		)
		(pad "264" smd rect
			(at 4.59994 106.249978 90)
			(size 1.8034 0.508)
			(layers "F.Cu" "F.Mask" "F.Paste")
			(net "M_A_DQ<48>")
		)
		(pad "265" smd rect
			(at 4.59994 107.100116 90)
			(size 1.8034 0.508)
			(layers "F.Cu" "F.Mask" "F.Paste")
			(net "GND")
		)
		(pad "266" smd rect
			(at 4.59994 107.95 90)
			(size 1.8034 0.508)
			(layers "F.Cu" "F.Mask" "F.Paste")
			(net "M_A_DQS_DN<6>")
		)
		(pad "267" smd rect
			(at 4.59994 108.799884 90)
			(size 1.8034 0.508)
			(layers "F.Cu" "F.Mask" "F.Paste")
			(net "M_A_DQS_DP<6>")
		)
		(pad "268" smd rect
			(at 4.59994 109.650022 90)
			(size 1.8034 0.508)
			(layers "F.Cu" "F.Mask" "F.Paste")
			(net "GND")
		)
		(pad "269" smd rect
			(at 4.59994 110.499906 90)
			(size 1.8034 0.508)
			(layers "F.Cu" "F.Mask" "F.Paste")
			(net "M_A_DQ<54>")
		)
		(pad "270" smd rect
			(at 4.59994 111.350044 90)
			(size 1.8034 0.508)
			(layers "F.Cu" "F.Mask" "F.Paste")
			(net "GND")
		)
		(pad "271" smd rect
			(at 4.59994 112.199928 90)
			(size 1.8034 0.508)
			(layers "F.Cu" "F.Mask" "F.Paste")
			(net "M_A_DQ<50>")
		)
		(pad "272" smd rect
			(at 4.59994 113.050066 90)
			(size 1.8034 0.508)
			(layers "F.Cu" "F.Mask" "F.Paste")
			(net "GND")
		)
		(pad "273" smd rect
			(at 4.59994 113.89995 90)
			(size 1.8034 0.508)
			(layers "F.Cu" "F.Mask" "F.Paste")
			(net "M_A_DQ<60>")
		)
		(pad "274" smd rect
			(at 4.59994 114.750088 90)
			(size 1.8034 0.508)
			(layers "F.Cu" "F.Mask" "F.Paste")
			(net "GND")
		)
		(pad "275" smd rect
			(at 4.59994 115.599972 90)
			(size 1.8034 0.508)
			(layers "F.Cu" "F.Mask" "F.Paste")
			(net "M_A_DQ<56>")
		)
		(pad "276" smd rect
			(at 4.59994 116.45011 90)
			(size 1.8034 0.508)
			(layers "F.Cu" "F.Mask" "F.Paste")
			(net "GND")
		)
		(pad "277" smd rect
			(at 4.59994 117.299994 90)
			(size 1.8034 0.508)
			(layers "F.Cu" "F.Mask" "F.Paste")
			(net "M_A_DQS_DN<7>")
		)
		(pad "278" smd rect
			(at 4.59994 118.149878 90)
			(size 1.8034 0.508)
			(layers "F.Cu" "F.Mask" "F.Paste")
			(net "M_A_DQS_DP<7>")
		)
		(pad "279" smd rect
			(at 4.59994 119.000016 90)
			(size 1.8034 0.508)
			(layers "F.Cu" "F.Mask" "F.Paste")
			(net "GND")
		)
		(pad "280" smd rect
			(at 4.59994 119.8499 90)
			(size 1.8034 0.508)
			(layers "F.Cu" "F.Mask" "F.Paste")
			(net "M_A_DQ<62>")
		)
		(pad "281" smd rect
			(at 4.59994 120.700038 90)
			(size 1.8034 0.508)
			(layers "F.Cu" "F.Mask" "F.Paste")
			(net "GND")
		)
		(pad "282" smd rect
			(at 4.59994 121.549922 90)
			(size 1.8034 0.508)
			(layers "F.Cu" "F.Mask" "F.Paste")
			(net "M_A_DQ<58>")
		)
		(pad "283" smd rect
			(at 4.59994 122.40006 90)
			(size 1.8034 0.508)
			(layers "F.Cu" "F.Mask" "F.Paste")
			(net "GND")
		)
		(pad "284" smd rect
			(at 4.59994 123.249944 90)
			(size 1.8034 0.508)
			(layers "F.Cu" "F.Mask" "F.Paste")
			(net "PVPP_ABC")
		)
		(pad "285" smd rect
			(at 4.59994 124.100082 90)
			(size 1.8034 0.508)
			(layers "F.Cu" "F.Mask" "F.Paste")
			(net "SMB_DDR_ABC_VPP_SDA")
		)
		(pad "286" smd rect
			(at 4.59994 124.949966 90)
			(size 1.8034 0.508)
			(layers "F.Cu" "F.Mask" "F.Paste")
			(net "PVPP_ABC")
		)
		(pad "287" smd rect
			(at 4.59994 125.800104 90)
			(size 1.8034 0.508)
			(layers "F.Cu" "F.Mask" "F.Paste")
			(net "PVPP_ABC")
		)
		(pad "288" smd rect
			(at 4.59994 126.649988 90)
			(size 1.8034 0.508)
			(layers "F.Cu" "F.Mask" "F.Paste")
			(net "PVPP_ABC")
		)
	)
)
